# SCM (Grand Teton) — schematic netlist excerpt (pin names and nets, part order shuffled) for the footprints in the layout excerpt that follows; sources: Cadence DE-HDL packaged netlist, KiCad conversion of 12092022_DA0F0TMDCD0_F0T_Management_Board_D_brd_V3_OCP.brd

C70  Q_CAP  0.1UF 25V 10% X7R  pkg 0402  page 16 : A = P1V2_AUX ; B = GND
R702  Q_RES  0 5% CHIP  pkg 0402LF  page 28 : A = RST_PLTRST_N ; B = RST_PLTRST_R2_N
C329  Q_CAP  22UF 16V 20% X6S  pkg C0805  page 10 : A = P12V_AUX ; B = GND

(kicad_pcb
	(version 20260206)
	(generator "pcbnew")
	(generator_version "10.0")
	(general
		(thickness 1.6)
		(legacy_teardrops no)
	)
	(paper "A4")
	(title_block
		(title "12092022_DA0F0TMDCD0_F0T_Management_Board_D_brd_V3_OCP.brd")
		(comment 1 "Grand Teton / footprints 1096-1098 of 1440")
	)
	(layers
		(0 "F.Cu" signal "TOP")
		(4 "In1.Cu" signal "GND")
		(6 "In2.Cu" signal "IN1")
		(8 "In3.Cu" signal "GND1")
		(10 "In4.Cu" signal "IN2")
		(12 "In5.Cu" signal "VCC")
		(14 "In6.Cu" signal "VCC1")
		(16 "In7.Cu" signal "IN3")
		(18 "In8.Cu" signal "GND2")
		(20 "In9.Cu" signal "IN4")
		(22 "In10.Cu" signal "GND3")
		(2 "B.Cu" signal "BOTTOM")
		(9 "F.Adhes" user "F.Adhesive")
		(11 "B.Adhes" user "B.Adhesive")
		(13 "F.Paste" user "Package Geometry/Pastemask Top")
		(15 "B.Paste" user "Package Geometry/Pastemask Bottom")
		(5 "F.SilkS" user "Ref Des/Silkscreen Top")
		(7 "B.SilkS" user "Ref Des/Silkscreen Bottom")
		(1 "F.Mask" user "Board Geometry/Soldermask Top")
		(3 "B.Mask" user "Board Geometry/Soldermask Bottom")
		(17 "Dwgs.User" user "User.Drawings")
		(19 "Cmts.User" user "User.Comments")
		(21 "Eco1.User" user "User.Eco1")
		(23 "Eco2.User" user "User.Eco2")
		(25 "Edge.Cuts" user "Board Geometry/Outline")
		(27 "Margin" user)
		(31 "F.CrtYd" user "Package Geometry/Place Bound Top")
		(29 "B.CrtYd" user "Package Geometry/Place Bound Bottom")
		(35 "F.Fab" user "Ref Des/Assembly Top")
		(33 "B.Fab" user "Ref Des/Assembly Bottom")
	)
	(footprint ""
		(layer "B.Cu")
		(at 49.420018 -49.808638 -90)
		(property "Reference" "C70"
			(at 0 0 90)
			(layer "B.SilkS")
			(hide yes)
			(effects
				(font
					(size 1.27 1.27)
				)
				(justify mirror)
			)
		)
		(property "Value" ""
			(at 0 0 90)
			(layer "B.Fab")
			(effects
				(font
					(size 1.27 1.27)
				)
				(justify mirror)
			)
		)
		(duplicate_pad_numbers_are_jumpers no)
		(fp_line
			(start -0.7874 0.4064)
			(end 0.7874 0.4064)
			(stroke
				(width 0.1524)
				(type default)
			)
			(layer "B.SilkS")
		)
		(fp_line
			(start 0.7874 0.4064)
			(end 0.7874 -0.4064)
			(stroke
				(width 0.1524)
				(type default)
			)
			(layer "B.SilkS")
		)
		(fp_line
			(start -0.7874 -0.4064)
			(end -0.7874 0.4064)
			(stroke
				(width 0.1524)
				(type default)
			)
			(layer "B.SilkS")
		)
		(fp_line
			(start 0.7874 -0.4064)
			(end -0.7874 -0.4064)
			(stroke
				(width 0.1524)
				(type default)
			)
			(layer "B.SilkS")
		)
		(fp_line
			(start -0.67945 0.3048)
			(end -0.120396 0.3048)
			(stroke
				(width 0.1)
				(type default)
			)
			(layer "B.Fab")
		)
		(fp_line
			(start -0.120396 0.3048)
			(end -0.120396 0.2794)
			(stroke
				(width 0.1)
				(type default)
			)
			(layer "B.Fab")
		)
		(fp_line
			(start 0.12065 0.3048)
			(end 0.67945 0.3048)
			(stroke
				(width 0.1)
				(type default)
			)
			(layer "B.Fab")
		)
		(fp_line
			(start 0.67945 0.3048)
			(end 0.67945 -0.305054)
			(stroke
				(width 0.1)
				(type default)
			)
			(layer "B.Fab")
		)
		(fp_line
			(start -0.120396 0.2794)
			(end 0.12065 0.2794)
			(stroke
				(width 0.1)
				(type default)
			)
			(layer "B.Fab")
		)
		(fp_line
			(start 0.12065 0.2794)
			(end 0.12065 0.3048)
			(stroke
				(width 0.1)
				(type default)
			)
			(layer "B.Fab")
		)
		(fp_line
			(start -0.12065 -0.2794)
			(end -0.12065 -0.3048)
			(stroke
				(width 0.1)
				(type default)
			)
			(layer "B.Fab")
		)
		(fp_line
			(start 0.12065 -0.2794)
			(end -0.12065 -0.2794)
			(stroke
				(width 0.1)
				(type default)
			)
			(layer "B.Fab")
		)
		(fp_line
			(start -0.67945 -0.3048)
			(end -0.67945 0.3048)
			(stroke
				(width 0.1)
				(type default)
			)
			(layer "B.Fab")
		)
		(fp_line
			(start -0.12065 -0.3048)
			(end -0.67945 -0.3048)
			(stroke
				(width 0.1)
				(type default)
			)
			(layer "B.Fab")
		)
		(fp_line
			(start 0.12065 -0.305054)
			(end 0.12065 -0.2794)
			(stroke
				(width 0.1)
				(type default)
			)
			(layer "B.Fab")
		)
		(fp_line
			(start 0.67945 -0.305054)
			(end 0.12065 -0.305054)
			(stroke
				(width 0.1)
				(type default)
			)
			(layer "B.Fab")
		)
		(pad "1" smd circle
			(at 0.40005 0 90)
			(size 0 0)
			(layers "B.Cu" "B.Mask" "B.Paste")
			(net "P1V2_AUX")
		)
		(pad "2" smd circle
			(at -0.40005 0 90)
			(size 0 0)
			(layers "B.Cu" "B.Mask" "B.Paste")
			(net "GND")
		)
	)
	(footprint ""
		(layer "B.Cu")
		(at 81.28 -101.473 90)
		(property "Reference" "C329"
			(at 0 0 90)
			(layer "B.SilkS")
			(hide yes)
			(effects
				(font
					(size 1.27 1.27)
				)
				(justify mirror)
			)
		)
		(property "Value" ""
			(at 0 0 90)
			(layer "B.Fab")
			(effects
				(font
					(size 1.27 1.27)
				)
				(justify mirror)
			)
		)
		(duplicate_pad_numbers_are_jumpers no)
		(fp_line
			(start 1.524 -0.762)
			(end -1.524 -0.762)
			(stroke
				(width 0.1524)
				(type default)
			)
			(layer "B.SilkS")
		)
		(fp_line
			(start -1.524 -0.762)
			(end -1.524 0.762)
			(stroke
				(width 0.1524)
				(type default)
			)
			(layer "B.SilkS")
		)
		(fp_line
			(start 1.524 0.762)
			(end 1.524 -0.762)
			(stroke
				(width 0.1524)
				(type default)
			)
			(layer "B.SilkS")
		)
		(fp_line
			(start -1.524 0.762)
			(end 1.524 0.762)
			(stroke
				(width 0.1524)
				(type default)
			)
			(layer "B.SilkS")
		)
		(fp_line
			(start 1.1049 -0.724916)
			(end 1.1049 0.724916)
			(stroke
				(width 0.1)
				(type default)
			)
			(layer "B.Fab")
		)
		(fp_line
			(start -1.1049 -0.724916)
			(end 1.1049 -0.724916)
			(stroke
				(width 0.1)
				(type default)
			)
			(layer "B.Fab")
		)
		(fp_line
			(start 1.1049 0.724916)
			(end -1.1049 0.724916)
			(stroke
				(width 0.1)
				(type default)
			)
			(layer "B.Fab")
		)
		(fp_line
			(start -1.1049 0.724916)
			(end -1.1049 -0.724916)
			(stroke
				(width 0.1)
				(type default)
			)
			(layer "B.Fab")
		)
		(pad "1" smd rect
			(at 0.889 0 90)
			(size 1.016 1.27)
			(layers "B.Cu" "B.Mask" "B.Paste")
			(net "P12V_AUX")
		)
		(pad "2" smd rect
			(at -0.889 0 90)
			(size 1.016 1.27)
			(layers "B.Cu" "B.Mask" "B.Paste")
			(net "GND")
		)
	)
	(footprint ""
		(layer "B.Cu")
		(at 51.3715 -86.9315 180)
		(property "Reference" "R702"
			(at 0 0 0)
			(layer "B.SilkS")
			(hide yes)
			(effects
				(font
					(size 1.27 1.27)
				)
				(justify mirror)
			)
		)
		(property "Value" ""
			(at 0 0 0)
			(layer "B.Fab")
			(effects
				(font
					(size 1.27 1.27)
				)
				(justify mirror)
			)
		)
		(duplicate_pad_numbers_are_jumpers no)
		(fp_line
			(start 0.7874 0.4064)
			(end 0.7874 -0.4064)
			(stroke
				(width 0.1524)
				(type default)
			)
			(layer "B.SilkS")
		)
		(fp_line
			(start 0.7874 -0.4064)
			(end -0.7874 -0.4064)
			(stroke
				(width 0.1524)
				(type default)
			)
			(layer "B.SilkS")
		)
		(fp_line
			(start -0.7874 0.4064)
			(end 0.7874 0.4064)
			(stroke
				(width 0.1524)
				(type default)
			)
			(layer "B.SilkS")
		)
		(fp_line
			(start -0.7874 -0.4064)
			(end -0.7874 0.4064)
			(stroke
				(width 0.1524)
				(type default)
			)
			(layer "B.SilkS")
		)
		(fp_line
			(start 0.67945 0.3048)
			(end 0.67945 -0.305054)
			(stroke
				(width 0.1)
				(type default)
			)
			(layer "B.Fab")
		)
		(fp_line
			(start 0.67945 -0.305054)
			(end 0.12065 -0.305054)
			(stroke
				(width 0.1)
				(type default)
			)
			(layer "B.Fab")
		)
		(fp_line
			(start 0.12065 0.3048)
			(end 0.67945 0.3048)
			(stroke
				(width 0.1)
				(type default)
			)
			(layer "B.Fab")
		)
		(fp_line
			(start 0.12065 0.2794)
			(end 0.12065 0.3048)
			(stroke
				(width 0.1)
				(type default)
			)
			(layer "B.Fab")
		)
		(fp_line
			(start 0.12065 -0.2794)
			(end -0.12065 -0.2794)
			(stroke
				(width 0.1)
				(type default)
			)
			(layer "B.Fab")
		)
		(fp_line
			(start 0.12065 -0.305054)
			(end 0.12065 -0.2794)
			(stroke
				(width 0.1)
				(type default)
			)
			(layer "B.Fab")
		)
		(fp_line
			(start -0.120396 0.3048)
			(end -0.120396 0.2794)
			(stroke
				(width 0.1)
				(type default)
			)
			(layer "B.Fab")
		)
		(fp_line
			(start -0.120396 0.2794)
			(end 0.12065 0.2794)
			(stroke
				(width 0.1)
				(type default)
			)
			(layer "B.Fab")
		)
		(fp_line
			(start -0.12065 -0.2794)
			(end -0.12065 -0.3048)
			(stroke
				(width 0.1)
				(type default)
			)
			(layer "B.Fab")
		)
		(fp_line
			(start -0.12065 -0.3048)
			(end -0.67945 -0.3048)
			(stroke
				(width 0.1)
				(type default)
			)
			(layer "B.Fab")
		)
		(fp_line
			(start -0.67945 0.3048)
			(end -0.120396 0.3048)
			(stroke
				(width 0.1)
				(type default)
			)
			(layer "B.Fab")
		)
		(fp_line
			(start -0.67945 -0.3048)
			(end -0.67945 0.3048)
			(stroke
				(width 0.1)
				(type default)
			)
			(layer "B.Fab")
		)
		(pad "1" smd circle
			(at 0.40005 0)
			(size 0 0)
			(layers "B.Cu" "B.Mask" "B.Paste")
			(net "RST_PLTRST_N")
		)
		(pad "2" smd circle
			(at -0.40005 0)
			(size 0 0)
			(layers "B.Cu" "B.Mask" "B.Paste")
			(net "RST_PLTRST_R2_N")
		)
	)
)
